# T6G (Grand Teton) — schematic netlist excerpt (pin names and nets, part order shuffled) for the footprints in the layout excerpt that follows; sources: Cadence DE-HDL packaged netlist, KiCad conversion of 04192023_DAF0TMB3IC0_F0TG_MB_C_brd_V02_OCP.brd

Q136  MOSFET_NCH_DUAL  PJT138K IC  pkg SOT363XD  page 124
  S1  = GND
  G1  = GPU_3V3IO_RSVD4
  D2  = GPU_3V3IO_RSVD4_ISO
  S2  = GND
  G2  = GPU_3V3IO_RSVD4_N
  D1  = GPU_3V3IO_RSVD4_N

PC6602  Q_CAP  0.1UF 25V 10% X7R  pkg 0402  page 362 : A = P0V9_RETIMER_CPU0_VINSEN ; B = GND

(kicad_pcb
	(version 20260206)
	(generator "pcbnew")
	(generator_version "10.0")
	(general
		(thickness 1.6)
		(legacy_teardrops no)
	)
	(paper "A4")
	(title_block
		(title "04192023_DAF0TMB3IC0_F0TG_MB_C_brd_V02_OCP.brd")
		(comment 1 "Grand Teton / footprints 1085-1086 of 8354")
	)
	(layers
		(0 "F.Cu" signal "TOP")
		(4 "In1.Cu" signal "GND")
		(6 "In2.Cu" signal "IN1")
		(8 "In3.Cu" signal "GND1")
		(10 "In4.Cu" signal "IN2")
		(12 "In5.Cu" signal "GND2")
		(14 "In6.Cu" signal "IN3")
		(16 "In7.Cu" signal "GND3")
		(18 "In8.Cu" signal "VCC")
		(20 "In9.Cu" signal "VCC1")
		(22 "In10.Cu" signal "GND4")
		(24 "In11.Cu" signal "IN4")
		(26 "In12.Cu" signal "GND5")
		(28 "In13.Cu" signal "IN5")
		(30 "In14.Cu" signal "GND6")
		(32 "In15.Cu" signal "IN6")
		(34 "In16.Cu" signal "GND7")
		(2 "B.Cu" signal "BOTTOM")
		(9 "F.Adhes" user "F.Adhesive")
		(11 "B.Adhes" user "B.Adhesive")
		(13 "F.Paste" user "Package Geometry/Pastemask Top")
		(15 "B.Paste" user "Package Geometry/Pastemask Bottom")
		(5 "F.SilkS" user "Ref Des/Silkscreen Top")
		(7 "B.SilkS" user "Ref Des/Silkscreen Bottom")
		(1 "F.Mask" user "Board Geometry/Soldermask Top")
		(3 "B.Mask" user "Board Geometry/Soldermask Bottom")
		(17 "Dwgs.User" user "User.Drawings")
		(19 "Cmts.User" user "User.Comments")
		(21 "Eco1.User" user "User.Eco1")
		(23 "Eco2.User" user "User.Eco2")
		(25 "Edge.Cuts" user "Board Geometry/Outline")
		(27 "Margin" user)
		(31 "F.CrtYd" user "Package Geometry/Place Bound Top")
		(29 "B.CrtYd" user "Package Geometry/Place Bound Bottom")
		(35 "F.Fab" user "Ref Des/Assembly Top")
		(33 "B.Fab" user "Ref Des/Assembly Bottom")
	)
	(footprint ""
		(layer "F.Cu")
		(at 449.443602 -426.255688)
		(property "Reference" "PC6602"
			(at 0 0 0)
			(layer "F.SilkS")
			(hide yes)
			(effects
				(font
					(size 1.27 1.27)
				)
			)
		)
		(property "Value" ""
			(at 0 0 0)
			(layer "F.Fab")
			(effects
				(font
					(size 1.27 1.27)
				)
			)
		)
		(duplicate_pad_numbers_are_jumpers no)
		(fp_line
			(start -0.7874 -0.4064)
			(end 0.7874 -0.4064)
			(stroke
				(width 0.1524)
				(type default)
			)
			(layer "F.SilkS")
		)
		(fp_line
			(start -0.7874 0.4064)
			(end -0.7874 -0.4064)
			(stroke
				(width 0.1524)
				(type default)
			)
			(layer "F.SilkS")
		)
		(fp_line
			(start 0.7874 -0.4064)
			(end 0.7874 0.4064)
			(stroke
				(width 0.1524)
				(type default)
			)
			(layer "F.SilkS")
		)
		(fp_line
			(start 0.7874 0.4064)
			(end -0.7874 0.4064)
			(stroke
				(width 0.1524)
				(type default)
			)
			(layer "F.SilkS")
		)
		(fp_line
			(start -0.67945 -0.305054)
			(end -0.12065 -0.305054)
			(stroke
				(width 0.1)
				(type default)
			)
			(layer "F.Fab")
		)
		(fp_line
			(start -0.67945 0.3048)
			(end -0.67945 -0.305054)
			(stroke
				(width 0.1)
				(type default)
			)
			(layer "F.Fab")
		)
		(fp_line
			(start -0.12065 -0.305054)
			(end -0.12065 -0.2794)
			(stroke
				(width 0.1)
				(type default)
			)
			(layer "F.Fab")
		)
		(fp_line
			(start -0.12065 -0.2794)
			(end 0.12065 -0.2794)
			(stroke
				(width 0.1)
				(type default)
			)
			(layer "F.Fab")
		)
		(fp_line
			(start -0.12065 0.2794)
			(end -0.12065 0.3048)
			(stroke
				(width 0.1)
				(type default)
			)
			(layer "F.Fab")
		)
		(fp_line
			(start -0.12065 0.3048)
			(end -0.67945 0.3048)
			(stroke
				(width 0.1)
				(type default)
			)
			(layer "F.Fab")
		)
		(fp_line
			(start 0.120396 0.2794)
			(end -0.12065 0.2794)
			(stroke
				(width 0.1)
				(type default)
			)
			(layer "F.Fab")
		)
		(fp_line
			(start 0.120396 0.3048)
			(end 0.120396 0.2794)
			(stroke
				(width 0.1)
				(type default)
			)
			(layer "F.Fab")
		)
		(fp_line
			(start 0.12065 -0.3048)
			(end 0.67945 -0.3048)
			(stroke
				(width 0.1)
				(type default)
			)
			(layer "F.Fab")
		)
		(fp_line
			(start 0.12065 -0.2794)
			(end 0.12065 -0.3048)
			(stroke
				(width 0.1)
				(type default)
			)
			(layer "F.Fab")
		)
		(fp_line
			(start 0.67945 -0.3048)
			(end 0.67945 0.3048)
			(stroke
				(width 0.1)
				(type default)
			)
			(layer "F.Fab")
		)
		(fp_line
			(start 0.67945 0.3048)
			(end 0.120396 0.3048)
			(stroke
				(width 0.1)
				(type default)
			)
			(layer "F.Fab")
		)
		(pad "1" smd circle
			(at -0.40005 0)
			(size 0 0)
			(layers "F.Cu" "F.Mask" "F.Paste")
			(net "P0V9_RETIMER_CPU0_VINSEN")
		)
		(pad "2" smd circle
			(at 0.40005 0)
			(size 0 0)
			(layers "F.Cu" "F.Mask" "F.Paste")
			(net "GND")
		)
	)
	(footprint ""
		(layer "F.Cu")
		(at 442.18352 -438.397396)
		(property "Reference" "Q136"
			(at -1.4224 -1.768348 0)
			(unlocked yes)
			(layer "F.SilkS")
			(effects
				(font
					(size 0.7874 0.5842)
					(thickness 0.1524)
				)
				(justify left)
			)
		)
		(property "Value" ""
			(at 0 0 0)
			(layer "F.Fab")
			(effects
				(font
					(size 1.27 1.27)
				)
			)
		)
		(duplicate_pad_numbers_are_jumpers no)
		(fp_line
			(start -1.332738 -1.100074)
			(end -0.4826 -1.100074)
			(stroke
				(width 0.1524)
				(type default)
			)
			(layer "F.SilkS")
		)
		(fp_line
			(start -1.332738 1.100074)
			(end -1.332738 -1.100074)
			(stroke
				(width 0.1524)
				(type default)
			)
			(layer "F.SilkS")
		)
		(fp_line
			(start -0.4826 -1.100074)
			(end 0 -0.541274)
			(stroke
				(width 0.1524)
				(type default)
			)
			(layer "F.SilkS")
		)
		(fp_line
			(start 0 -0.541274)
			(end 0.4826 -1.100074)
			(stroke
				(width 0.1524)
				(type default)
			)
			(layer "F.SilkS")
		)
		(fp_line
			(start 0.4826 -1.100074)
			(end 1.332738 -1.100074)
			(stroke
				(width 0.1524)
				(type default)
			)
			(layer "F.SilkS")
		)
		(fp_line
			(start 1.332738 -1.100074)
			(end 1.332738 1.100074)
			(stroke
				(width 0.1524)
				(type default)
			)
			(layer "F.SilkS")
		)
		(fp_line
			(start 1.332738 1.100074)
			(end -1.332738 1.100074)
			(stroke
				(width 0.1524)
				(type default)
			)
			(layer "F.SilkS")
		)
		(fp_poly
			(pts
				(xy -1.467104 -1.284986) (xy -2.16916 -0.933958) (xy -2.16916 -1.636014)
			)
			(stroke
				(width 0)
				(type default)
			)
			(fill yes)
			(layer "F.SilkS")
		)
		(fp_line
			(start -0.674878 -1.100074)
			(end 0.674878 -1.100074)
			(stroke
				(width 0.1)
				(type default)
			)
			(layer "F.Fab")
		)
		(fp_line
			(start -0.674878 1.100074)
			(end -0.674878 -1.100074)
			(stroke
				(width 0.1)
				(type default)
			)
			(layer "F.Fab")
		)
		(fp_line
			(start 0.674878 -1.100074)
			(end 0.674878 1.100074)
			(stroke
				(width 0.1)
				(type default)
			)
			(layer "F.Fab")
		)
		(fp_line
			(start 0.674878 1.100074)
			(end -0.674878 1.100074)
			(stroke
				(width 0.1)
				(type default)
			)
			(layer "F.Fab")
		)
		(fp_poly
			(pts
				(xy -2.2352 -0.298958) (xy -2.2352 -1.001014) (xy -1.533144 -0.649986)
			)
			(stroke
				(width 0)
				(type default)
			)
			(fill yes)
			(layer "F.Fab")
		)
		(pad "1" smd rect
			(at -0.94996 -0.649986 90)
			(size 0.4318 0.508)
			(layers "F.Cu" "F.Mask" "F.Paste")
			(net "GND")
		)
		(pad "2" smd rect
			(at -0.94996 0 90)
			(size 0.4318 0.508)
			(layers "F.Cu" "F.Mask" "F.Paste")
			(net "GPU_3V3IO_RSVD4")
		)
		(pad "3" smd rect
			(at -0.94996 0.649986 90)
			(size 0.4318 0.508)
			(layers "F.Cu" "F.Mask" "F.Paste")
			(net "GPU_3V3IO_RSVD4_ISO")
		)
		(pad "4" smd rect
			(at 0.94996 0.649986 90)
			(size 0.4318 0.508)
			(layers "F.Cu" "F.Mask" "F.Paste")
			(net "GND")
		)
		(pad "5" smd rect
			(at 0.94996 0 90)
			(size 0.4318 0.508)
			(layers "F.Cu" "F.Mask" "F.Paste")
			(net "GPU_3V3IO_RSVD4_N")
		)
		(pad "6" smd rect
			(at 0.94996 -0.649986 90)
			(size 0.4318 0.508)
			(layers "F.Cu" "F.Mask" "F.Paste")
			(net "GPU_3V3IO_RSVD4_N")
		)
	)
)
